(kicad_pcb
	(version 20260206)
	(generator "pcbnew")
	(generator_version "10.0")
	(general
		(thickness 1.6)
		(legacy_teardrops no)
	)
	(paper "A4")
	(title_block
		(title "9052_F0T_PDB_Converter_Brick_F_V03_1208_1600_OCP.brd")
		(comment 1 "Grand Teton / footprints 439-443 of 578")
	)
	(layers
		(0 "F.Cu" signal "TOP")
		(4 "In1.Cu" signal "GND")
		(6 "In2.Cu" signal "IN1")
		(8 "In3.Cu" signal "GND1")
		(10 "In4.Cu" signal "VCC")
		(12 "In5.Cu" signal "VCC1")
		(14 "In6.Cu" signal "GND2")
		(16 "In7.Cu" signal "IN2")
		(18 "In8.Cu" signal "GND3")
		(2 "B.Cu" signal "BOTTOM")
		(9 "F.Adhes" user "F.Adhesive")
		(11 "B.Adhes" user "B.Adhesive")
		(13 "F.Paste" user "Package Geometry/Pastemask Top")
		(15 "B.Paste" user "Package Geometry/Pastemask Bottom")
		(5 "F.SilkS" user "Ref Des/Silkscreen Top")
		(7 "B.SilkS" user "Ref Des/Silkscreen Bottom")
		(1 "F.Mask" user "Board Geometry/Soldermask Top")
		(3 "B.Mask" user "Board Geometry/Soldermask Bottom")
		(17 "Dwgs.User" user "User.Drawings")
		(19 "Cmts.User" user "User.Comments")
		(21 "Eco1.User" user "User.Eco1")
		(23 "Eco2.User" user "User.Eco2")
		(25 "Edge.Cuts" user "Board Geometry/Outline")
		(27 "Margin" user)
		(31 "F.CrtYd" user "Package Geometry/Place Bound Top")
		(29 "B.CrtYd" user "Package Geometry/Place Bound Bottom")
		(35 "F.Fab" user "Ref Des/Assembly Top")
		(33 "B.Fab" user "Ref Des/Assembly Bottom")
	)
	(footprint ""
		(layer "B.Cu")
		(at 271.78 -47.625 -90)
		(property "Reference" "R159"
			(at 0 0 90)
			(layer "B.SilkS")
			(hide yes)
			(effects
				(font
					(size 1.27 1.27)
				)
				(justify mirror)
			)
		)
		(property "Value" ""
			(at 0 0 90)
			(layer "B.Fab")
			(effects
				(font
					(size 1.27 1.27)
				)
				(justify mirror)
			)
		)
		(duplicate_pad_numbers_are_jumpers no)
		(fp_line
			(start -0.7874 0.4064)
			(end 0.7874 0.4064)
			(stroke
				(width 0.1524)
				(type default)
			)
			(layer "B.SilkS")
		)
		(fp_line
			(start 0.7874 0.4064)
			(end 0.7874 -0.4064)
			(stroke
				(width 0.1524)
				(type default)
			)
			(layer "B.SilkS")
		)
		(fp_line
			(start -0.7874 -0.4064)
			(end -0.7874 0.4064)
			(stroke
				(width 0.1524)
				(type default)
			)
			(layer "B.SilkS")
		)
		(fp_line
			(start 0.7874 -0.4064)
			(end -0.7874 -0.4064)
			(stroke
				(width 0.1524)
				(type default)
			)
			(layer "B.SilkS")
		)
		(fp_line
			(start -0.67945 0.3048)
			(end -0.120396 0.3048)
			(stroke
				(width 0.1)
				(type default)
			)
			(layer "B.Fab")
		)
		(fp_line
			(start -0.120396 0.3048)
			(end -0.120396 0.2794)
			(stroke
				(width 0.1)
				(type default)
			)
			(layer "B.Fab")
		)
		(fp_line
			(start 0.12065 0.3048)
			(end 0.67945 0.3048)
			(stroke
				(width 0.1)
				(type default)
			)
			(layer "B.Fab")
		)
		(fp_line
			(start 0.67945 0.3048)
			(end 0.67945 -0.305054)
			(stroke
				(width 0.1)
				(type default)
			)
			(layer "B.Fab")
		)
		(fp_line
			(start -0.120396 0.2794)
			(end 0.12065 0.2794)
			(stroke
				(width 0.1)
				(type default)
			)
			(layer "B.Fab")
		)
		(fp_line
			(start 0.12065 0.2794)
			(end 0.12065 0.3048)
			(stroke
				(width 0.1)
				(type default)
			)
			(layer "B.Fab")
		)
		(fp_line
			(start -0.12065 -0.2794)
			(end -0.12065 -0.3048)
			(stroke
				(width 0.1)
				(type default)
			)
			(layer "B.Fab")
		)
		(fp_line
			(start 0.12065 -0.2794)
			(end -0.12065 -0.2794)
			(stroke
				(width 0.1)
				(type default)
			)
			(layer "B.Fab")
		)
		(fp_line
			(start -0.67945 -0.3048)
			(end -0.67945 0.3048)
			(stroke
				(width 0.1)
				(type default)
			)
			(layer "B.Fab")
		)
		(fp_line
			(start -0.12065 -0.3048)
			(end -0.67945 -0.3048)
			(stroke
				(width 0.1)
				(type default)
			)
			(layer "B.Fab")
		)
		(fp_line
			(start 0.12065 -0.305054)
			(end 0.12065 -0.2794)
			(stroke
				(width 0.1)
				(type default)
			)
			(layer "B.Fab")
		)
		(fp_line
			(start 0.67945 -0.305054)
			(end 0.12065 -0.305054)
			(stroke
				(width 0.1)
				(type default)
			)
			(layer "B.Fab")
		)
		(pad "1" smd circle
			(at 0.40005 0 90)
			(size 0 0)
			(layers "B.Cu" "B.Mask" "B.Paste")
			(net "P52V_HS1_ADR1")
		)
		(pad "2" smd circle
			(at -0.40005 0 90)
			(size 0 0)
			(layers "B.Cu" "B.Mask" "B.Paste")
			(net "GND_FIELD_SIGNAL")
		)
	)
	(footprint ""
		(layer "B.Cu")
		(at 285.496 -54.483)
		(property "Reference" "PR18"
			(at 0 0 0)
			(layer "B.SilkS")
			(hide yes)
			(effects
				(font
					(size 1.27 1.27)
				)
				(justify mirror)
			)
		)
		(property "Value" ""
			(at 0 0 0)
			(layer "B.Fab")
			(effects
				(font
					(size 1.27 1.27)
				)
				(justify mirror)
			)
		)
		(duplicate_pad_numbers_are_jumpers no)
		(fp_line
			(start -1.651 -0.8382)
			(end -1.651 0.8382)
			(stroke
				(width 0.1524)
				(type default)
			)
			(layer "B.SilkS")
		)
		(fp_line
			(start -1.651 0.8382)
			(end 1.651 0.8382)
			(stroke
				(width 0.1524)
				(type default)
			)
			(layer "B.SilkS")
		)
		(fp_line
			(start 1.651 -0.8382)
			(end -1.651 -0.8382)
			(stroke
				(width 0.1524)
				(type default)
			)
			(layer "B.SilkS")
		)
		(fp_line
			(start 1.651 0.8382)
			(end 1.651 -0.8382)
			(stroke
				(width 0.1524)
				(type default)
			)
			(layer "B.SilkS")
		)
		(fp_line
			(start -1.560576 -0.7366)
			(end -1.524 -0.7366)
			(stroke
				(width 0.1)
				(type default)
			)
			(layer "B.Fab")
		)
		(fp_line
			(start -1.560576 0.7366)
			(end -1.560576 -0.7366)
			(stroke
				(width 0.1)
				(type default)
			)
			(layer "B.Fab")
		)
		(fp_line
			(start -1.524 -0.7366)
			(end 1.524 -0.7366)
			(stroke
				(width 0.1)
				(type default)
			)
			(layer "B.Fab")
		)
		(fp_line
			(start -1.524 0.7366)
			(end -1.560576 0.7366)
			(stroke
				(width 0.1)
				(type default)
			)
			(layer "B.Fab")
		)
		(fp_line
			(start 1.524 -0.7366)
			(end 1.559814 -0.7366)
			(stroke
				(width 0.1)
				(type default)
			)
			(layer "B.Fab")
		)
		(fp_line
			(start 1.524 0.7366)
			(end -1.524 0.7366)
			(stroke
				(width 0.1)
				(type default)
			)
			(layer "B.Fab")
		)
		(fp_line
			(start 1.559814 -0.7366)
			(end 1.559814 0.7366)
			(stroke
				(width 0.1)
				(type default)
			)
			(layer "B.Fab")
		)
		(fp_line
			(start 1.559814 0.7366)
			(end 1.524 0.7366)
			(stroke
				(width 0.1)
				(type default)
			)
			(layer "B.Fab")
		)
		(pad "1" smd rect
			(at 0.94996 0)
			(size 1.1176 1.3716)
			(layers "B.Cu" "B.Mask" "B.Paste")
			(net "P52V_1")
		)
		(pad "2" smd rect
			(at -0.94996 0)
			(size 1.1176 1.3716)
			(layers "B.Cu" "B.Mask" "B.Paste")
			(net "P52V_HS1_ISET")
		)
	)
	(footprint ""
		(layer "B.Cu")
		(at 146.558 -116.205)
		(property "Reference" "R167"
			(at 0 0 0)
			(layer "B.SilkS")
			(hide yes)
			(effects
				(font
					(size 1.27 1.27)
				)
				(justify mirror)
			)
		)
		(property "Value" ""
			(at 0 0 0)
			(layer "B.Fab")
			(effects
				(font
					(size 1.27 1.27)
				)
				(justify mirror)
			)
		)
		(duplicate_pad_numbers_are_jumpers no)
		(fp_line
			(start -0.7874 -0.4064)
			(end -0.7874 0.4064)
			(stroke
				(width 0.1524)
				(type default)
			)
			(layer "B.SilkS")
		)
		(fp_line
			(start -0.7874 0.4064)
			(end 0.7874 0.4064)
			(stroke
				(width 0.1524)
				(type default)
			)
			(layer "B.SilkS")
		)
		(fp_line
			(start 0.7874 -0.4064)
			(end -0.7874 -0.4064)
			(stroke
				(width 0.1524)
				(type default)
			)
			(layer "B.SilkS")
		)
		(fp_line
			(start 0.7874 0.4064)
			(end 0.7874 -0.4064)
			(stroke
				(width 0.1524)
				(type default)
			)
			(layer "B.SilkS")
		)
		(fp_line
			(start -0.67945 -0.3048)
			(end -0.67945 0.3048)
			(stroke
				(width 0.1)
				(type default)
			)
			(layer "B.Fab")
		)
		(fp_line
			(start -0.67945 0.3048)
			(end -0.120396 0.3048)
			(stroke
				(width 0.1)
				(type default)
			)
			(layer "B.Fab")
		)
		(fp_line
			(start -0.12065 -0.3048)
			(end -0.67945 -0.3048)
			(stroke
				(width 0.1)
				(type default)
			)
			(layer "B.Fab")
		)
		(fp_line
			(start -0.12065 -0.2794)
			(end -0.12065 -0.3048)
			(stroke
				(width 0.1)
				(type default)
			)
			(layer "B.Fab")
		)
		(fp_line
			(start -0.120396 0.2794)
			(end 0.12065 0.2794)
			(stroke
				(width 0.1)
				(type default)
			)
			(layer "B.Fab")
		)
		(fp_line
			(start -0.120396 0.3048)
			(end -0.120396 0.2794)
			(stroke
				(width 0.1)
				(type default)
			)
			(layer "B.Fab")
		)
		(fp_line
			(start 0.12065 -0.305054)
			(end 0.12065 -0.2794)
			(stroke
				(width 0.1)
				(type default)
			)
			(layer "B.Fab")
		)
		(fp_line
			(start 0.12065 -0.2794)
			(end -0.12065 -0.2794)
			(stroke
				(width 0.1)
				(type default)
			)
			(layer "B.Fab")
		)
		(fp_line
			(start 0.12065 0.2794)
			(end 0.12065 0.3048)
			(stroke
				(width 0.1)
				(type default)
			)
			(layer "B.Fab")
		)
		(fp_line
			(start 0.12065 0.3048)
			(end 0.67945 0.3048)
			(stroke
				(width 0.1)
				(type default)
			)
			(layer "B.Fab")
		)
		(fp_line
			(start 0.67945 -0.305054)
			(end 0.12065 -0.305054)
			(stroke
				(width 0.1)
				(type default)
			)
			(layer "B.Fab")
		)
		(fp_line
			(start 0.67945 0.3048)
			(end 0.67945 -0.305054)
			(stroke
				(width 0.1)
				(type default)
			)
			(layer "B.Fab")
		)
		(pad "1" smd circle
			(at 0.40005 0 180)
			(size 0 0)
			(layers "B.Cu" "B.Mask" "B.Paste")
			(net "PWRGD_P52V_HS1_PG_N")
		)
		(pad "2" smd circle
			(at -0.40005 0 180)
			(size 0 0)
			(layers "B.Cu" "B.Mask" "B.Paste")
			(net "BRICK_P12V0_EN_N")
		)
	)
	(footprint ""
		(layer "B.Cu")
		(at 202.946 -85.09 180)
		(property "Reference" "R130"
			(at 0 0 0)
			(layer "B.SilkS")
			(hide yes)
			(effects
				(font
					(size 1.27 1.27)
				)
				(justify mirror)
			)
		)
		(property "Value" ""
			(at 0 0 0)
			(layer "B.Fab")
			(effects
				(font
					(size 1.27 1.27)
				)
				(justify mirror)
			)
		)
		(duplicate_pad_numbers_are_jumpers no)
		(fp_line
			(start 0.7874 0.4064)
			(end 0.7874 -0.4064)
			(stroke
				(width 0.1524)
				(type default)
			)
			(layer "B.SilkS")
		)
		(fp_line
			(start 0.7874 -0.4064)
			(end -0.7874 -0.4064)
			(stroke
				(width 0.1524)
				(type default)
			)
			(layer "B.SilkS")
		)
		(fp_line
			(start -0.7874 0.4064)
			(end 0.7874 0.4064)
			(stroke
				(width 0.1524)
				(type default)
			)
			(layer "B.SilkS")
		)
		(fp_line
			(start -0.7874 -0.4064)
			(end -0.7874 0.4064)
			(stroke
				(width 0.1524)
				(type default)
			)
			(layer "B.SilkS")
		)
		(fp_line
			(start 0.67945 0.3048)
			(end 0.67945 -0.305054)
			(stroke
				(width 0.1)
				(type default)
			)
			(layer "B.Fab")
		)
		(fp_line
			(start 0.67945 -0.305054)
			(end 0.12065 -0.305054)
			(stroke
				(width 0.1)
				(type default)
			)
			(layer "B.Fab")
		)
		(fp_line
			(start 0.12065 0.3048)
			(end 0.67945 0.3048)
			(stroke
				(width 0.1)
				(type default)
			)
			(layer "B.Fab")
		)
		(fp_line
			(start 0.12065 0.2794)
			(end 0.12065 0.3048)
			(stroke
				(width 0.1)
				(type default)
			)
			(layer "B.Fab")
		)
		(fp_line
			(start 0.12065 -0.2794)
			(end -0.12065 -0.2794)
			(stroke
				(width 0.1)
				(type default)
			)
			(layer "B.Fab")
		)
		(fp_line
			(start 0.12065 -0.305054)
			(end 0.12065 -0.2794)
			(stroke
				(width 0.1)
				(type default)
			)
			(layer "B.Fab")
		)
		(fp_line
			(start -0.120396 0.3048)
			(end -0.120396 0.2794)
			(stroke
				(width 0.1)
				(type default)
			)
			(layer "B.Fab")
		)
		(fp_line
			(start -0.120396 0.2794)
			(end 0.12065 0.2794)
			(stroke
				(width 0.1)
				(type default)
			)
			(layer "B.Fab")
		)
		(fp_line
			(start -0.12065 -0.2794)
			(end -0.12065 -0.3048)
			(stroke
				(width 0.1)
				(type default)
			)
			(layer "B.Fab")
		)
		(fp_line
			(start -0.12065 -0.3048)
			(end -0.67945 -0.3048)
			(stroke
				(width 0.1)
				(type default)
			)
			(layer "B.Fab")
		)
		(fp_line
			(start -0.67945 0.3048)
			(end -0.120396 0.3048)
			(stroke
				(width 0.1)
				(type default)
			)
			(layer "B.Fab")
		)
		(fp_line
			(start -0.67945 -0.3048)
			(end -0.67945 0.3048)
			(stroke
				(width 0.1)
				(type default)
			)
			(layer "B.Fab")
		)
		(pad "1" smd circle
			(at 0.40005 0)
			(size 0 0)
			(layers "B.Cu" "B.Mask" "B.Paste")
			(net "SMB_HPDB_MISC_SDA")
		)
		(pad "2" smd circle
			(at -0.40005 0)
			(size 0 0)
			(layers "B.Cu" "B.Mask" "B.Paste")
			(net "P3V3_AUX")
		)
	)
	(footprint ""
		(layer "B.Cu")
		(at 300.624494 -36.438586 -90)
		(property "Reference" "PD6"
			(at 7.001256 -0.117094 0)
			(unlocked yes)
			(layer "B.SilkS")
			(effects
				(font
					(size 0.7874 0.5842)
					(thickness 0.1524)
				)
				(justify left mirror)
			)
		)
		(property "Value" ""
			(at 0 0 90)
			(layer "B.Fab")
			(effects
				(font
					(size 1.27 1.27)
				)
				(justify mirror)
			)
		)
		(duplicate_pad_numbers_are_jumpers no)
		(fp_line
			(start -5.4102 3.109976)
			(end -5.4102 2.047494)
			(stroke
				(width 0.1524)
				(type default)
			)
			(layer "B.SilkS")
		)
		(fp_line
			(start -4.794504 3.109976)
			(end -3.554984 3.109976)
			(stroke
				(width 0.1524)
				(type default)
			)
			(layer "B.SilkS")
		)
		(fp_line
			(start -4.769104 3.109976)
			(end 4.664456 3.109976)
			(stroke
				(width 0.1524)
				(type default)
			)
			(layer "B.SilkS")
		)
		(fp_line
			(start -4.743704 3.109976)
			(end -5.4102 3.109976)
			(stroke
				(width 0.1524)
				(type default)
			)
			(layer "B.SilkS")
		)
		(fp_line
			(start -4.743704 3.109976)
			(end -4.6101 3.109976)
			(stroke
				(width 0.1524)
				(type default)
			)
			(layer "B.SilkS")
		)
		(fp_line
			(start -4.156202 3.109976)
			(end -4.183126 3.109976)
			(stroke
				(width 0.1524)
				(type default)
			)
			(layer "B.SilkS")
		)
		(fp_line
			(start 4.664456 3.109976)
			(end 4.664456 -3.109976)
			(stroke
				(width 0.1524)
				(type default)
			)
			(layer "B.SilkS")
		)
		(fp_line
			(start -4.715002 3.035554)
			(end -4.7117 2.984754)
			(stroke
				(width 0.1524)
				(type default)
			)
			(layer "B.SilkS")
		)
		(fp_line
			(start -5.313426 1.996694)
			(end -5.313426 3.109976)
			(stroke
				(width 0.1524)
				(type default)
			)
			(layer "B.SilkS")
		)
		(fp_line
			(start -5.262626 1.996694)
			(end -5.262626 3.109976)
			(stroke
				(width 0.1524)
				(type default)
			)
			(layer "B.SilkS")
		)
		(fp_line
			(start -5.211826 1.996694)
			(end -5.211826 3.109976)
			(stroke
				(width 0.1524)
				(type default)
			)
			(layer "B.SilkS")
		)
		(fp_line
			(start -0.762 1.27)
			(end -0.762 -1.27)
			(stroke
				(width 0.1524)
				(type default)
			)
			(layer "B.SilkS")
		)
		(fp_line
			(start -5.4102 1.107694)
			(end -5.4102 -0.822706)
			(stroke
				(width 0.1524)
				(type default)
			)
			(layer "B.SilkS")
		)
		(fp_line
			(start 0.508 1.016)
			(end 0.508 -1.016)
			(stroke
				(width 0.1524)
				(type default)
			)
			(layer "B.SilkS")
		)
		(fp_line
			(start -0.762 0)
			(end 0.508 1.016)
			(stroke
				(width 0.1524)
				(type default)
			)
			(layer "B.SilkS")
		)
		(fp_line
			(start -0.762 0)
			(end -1.2192 0)
			(stroke
				(width 0.1524)
				(type default)
			)
			(layer "B.SilkS")
		)
		(fp_line
			(start 1.0668 0)
			(end 0.6096 0)
			(stroke
				(width 0.1524)
				(type default)
			)
			(layer "B.SilkS")
		)
		(fp_line
			(start -5.313426 -0.822706)
			(end -5.313426 1.107694)
			(stroke
				(width 0.1524)
				(type default)
			)
			(layer "B.SilkS")
		)
		(fp_line
			(start -5.262626 -0.822706)
			(end -5.262626 1.107694)
			(stroke
				(width 0.1524)
				(type default)
			)
			(layer "B.SilkS")
		)
		(fp_line
			(start -5.211826 -0.822706)
			(end -5.211826 1.107694)
			(stroke
				(width 0.1524)
				(type default)
			)
			(layer "B.SilkS")
		)
		(fp_line
			(start 0.508 -1.016)
			(end -0.762 0)
			(stroke
				(width 0.1524)
				(type default)
			)
			(layer "B.SilkS")
		)
		(fp_line
			(start -5.4102 -1.762506)
			(end -5.4102 -3.109976)
			(stroke
				(width 0.1524)
				(type default)
			)
			(layer "B.SilkS")
		)
		(fp_line
			(start -5.4102 -3.109976)
			(end -4.783074 -3.109976)
			(stroke
				(width 0.1524)
				(type default)
			)
			(layer "B.SilkS")
		)
		(fp_line
			(start -5.313426 -3.109976)
			(end -5.313426 -1.762506)
			(stroke
				(width 0.1524)
				(type default)
			)
			(layer "B.SilkS")
		)
		(fp_line
			(start -5.262626 -3.109976)
			(end -5.262626 -1.762506)
			(stroke
				(width 0.1524)
				(type default)
			)
			(layer "B.SilkS")
		)
		(fp_line
			(start -5.211826 -3.109976)
			(end -5.211826 -1.762506)
			(stroke
				(width 0.1524)
				(type default)
			)
			(layer "B.SilkS")
		)
		(fp_line
			(start -5.110226 -3.109976)
			(end -5.110226 3.109976)
			(stroke
				(width 0.1524)
				(type default)
			)
			(layer "B.SilkS")
		)
		(fp_line
			(start -5.008626 -3.109976)
			(end -5.008626 3.109976)
			(stroke
				(width 0.1524)
				(type default)
			)
			(layer "B.SilkS")
		)
		(fp_line
			(start -4.932426 -3.109976)
			(end -4.932426 3.109976)
			(stroke
				(width 0.1524)
				(type default)
			)
			(layer "B.SilkS")
		)
		(fp_line
			(start -4.805426 -3.109976)
			(end -4.805426 3.109976)
			(stroke
				(width 0.1524)
				(type default)
			)
			(layer "B.SilkS")
		)
		(fp_line
			(start -4.70535 -3.109976)
			(end -4.70535 3.109976)
			(stroke
				(width 0.1524)
				(type default)
			)
			(layer "B.SilkS")
		)
		(fp_line
			(start -4.70535 -3.109976)
			(end -4.70535 3.109976)
			(stroke
				(width 0.1524)
				(type default)
			)
			(layer "B.SilkS")
		)
		(fp_line
			(start -4.70535 -3.109976)
			(end -4.70535 3.109976)
			(stroke
				(width 0.1524)
				(type default)
			)
			(layer "B.SilkS")
		)
		(fp_line
			(start -4.695444 -3.109976)
			(end -4.695444 3.109976)
			(stroke
				(width 0.1524)
				(type default)
			)
			(layer "B.SilkS")
		)
		(fp_line
			(start -4.6101 -3.109976)
			(end -4.283202 -3.109976)
			(stroke
				(width 0.1524)
				(type default)
			)
			(layer "B.SilkS")
		)
		(fp_line
			(start -4.511802 -3.109976)
			(end -4.207002 -3.109976)
			(stroke
				(width 0.1524)
				(type default)
			)
			(layer "B.SilkS")
		)
		(fp_line
			(start -4.183126 -3.109976)
			(end -4.794504 -3.109976)
			(stroke
				(width 0.1524)
				(type default)
			)
			(layer "B.SilkS")
		)
		(fp_line
			(start 4.664456 -3.109976)
			(end -4.743704 -3.109976)
			(stroke
				(width 0.1524)
				(type default)
			)
			(layer "B.SilkS")
		)
		(fp_line
			(start -4.065016 3.109976)
			(end 4.065016 3.109976)
			(stroke
				(width 0.1)
				(type default)
			)
			(layer "B.Fab")
		)
		(fp_line
			(start 4.065016 3.109976)
			(end 4.065016 -3.109976)
			(stroke
				(width 0.1)
				(type default)
			)
			(layer "B.Fab")
		)
		(fp_line
			(start -4.065016 -3.109976)
			(end -4.065016 3.109976)
			(stroke
				(width 0.1)
				(type default)
			)
			(layer "B.Fab")
		)
		(fp_line
			(start 4.065016 -3.109976)
			(end -4.065016 -3.109976)
			(stroke
				(width 0.1)
				(type default)
			)
			(layer "B.Fab")
		)
		(fp_text user "-"
			(at -7.122414 -2.815844 90)
			(unlocked yes)
			(layer "B.SilkS")
			(effects
				(font
					(size 1.905 1.4224)
					(thickness 0.1524)
				)
				(justify left mirror)
			)
		)
		(fp_text user "+"
			(at 3.850894 -3.69443 90)
			(unlocked yes)
			(layer "B.SilkS")
			(effects
				(font
					(size 1.905 1.4224)
					(thickness 0.1524)
				)
				(justify left mirror)
			)
		)
		(fp_text user "-"
			(at -6.643624 0.40005 90)
			(unlocked yes)
			(layer "B.Fab")
			(effects
				(font
					(size 1.905 1.4224)
					(thickness 0.1524)
				)
				(justify left mirror)
			)
		)
		(fp_text user "+"
			(at 4.5974 0.24765 90)
			(unlocked yes)
			(layer "B.Fab")
			(effects
				(font
					(size 1.905 1.4224)
					(thickness 0.1524)
				)
				(justify left mirror)
			)
		)
		(pad "A" smd rect
			(at 3.299968 0 270)
			(size 2.413 3.302)
			(layers "B.Cu" "B.Mask" "B.Paste")
			(net "GND")
		)
		(pad "C" smd rect
			(at -3.299968 0 270)
			(size 2.413 3.302)
			(layers "B.Cu" "B.Mask" "B.Paste")
			(net "P52V_1_FUSE_1")
		)
	)
)
